(kicad_sch (version 20230121) (generator eeschema)

  (paper "A3")

  (title_block
    (title "ECP5 - Datacenter Secure Control Module (DC-SCM)")
    (date "2024-07-15")
    (rev "1.2.1")
  )

  (junction (at 214.63 54.61) (diameter 0) (color 0 0 0 0)
  )
  (junction (at 176.53 189.23) (diameter 0) (color 0 0 0 0)
  )
  (junction (at 214.63 227.33) (diameter 0) (color 0 0 0 0)
  )
  (junction (at 214.63 212.09) (diameter 0) (color 0 0 0 0)
  )
  (junction (at 176.53 234.95) (diameter 0) (color 0 0 0 0)
  )
  (junction (at 214.63 265.43) (diameter 0) (color 0 0 0 0)
  )
  (junction (at 214.63 120.65) (diameter 0) (color 0 0 0 0)
  )
  (junction (at 176.53 46.99) (diameter 0) (color 0 0 0 0)
  )
  (junction (at 214.63 62.23) (diameter 0) (color 0 0 0 0)
  )
  (junction (at 176.53 257.81) (diameter 0) (color 0 0 0 0)
  )
  (junction (at 214.63 219.71) (diameter 0) (color 0 0 0 0)
  )
  (junction (at 214.63 143.51) (diameter 0) (color 0 0 0 0)
  )
  (junction (at 214.63 250.19) (diameter 0) (color 0 0 0 0)
  )
  (junction (at 176.53 69.85) (diameter 0) (color 0 0 0 0)
  )
  (junction (at 176.53 250.19) (diameter 0) (color 0 0 0 0)
  )
  (junction (at 214.63 234.95) (diameter 0) (color 0 0 0 0)
  )
  (junction (at 214.63 257.81) (diameter 0) (color 0 0 0 0)
  )
  (junction (at 176.53 110.49) (diameter 0) (color 0 0 0 0)
  )
  (junction (at 214.63 166.37) (diameter 0) (color 0 0 0 0)
  )
  (junction (at 214.63 179.07) (diameter 0) (color 0 0 0 0)
  )
  (junction (at 176.53 265.43) (diameter 0) (color 0 0 0 0)
  )
  (junction (at 214.63 102.87) (diameter 0) (color 0 0 0 0)
  )
  (junction (at 176.53 242.57) (diameter 0) (color 0 0 0 0)
  )
  (junction (at 176.53 133.35) (diameter 0) (color 0 0 0 0)
  )
  (junction (at 176.53 118.11) (diameter 0) (color 0 0 0 0)
  )
  (junction (at 176.53 166.37) (diameter 0) (color 0 0 0 0)
  )
  (junction (at 176.53 125.73) (diameter 0) (color 0 0 0 0)
  )
  (junction (at 214.63 242.57) (diameter 0) (color 0 0 0 0)
  )

  (no_connect (at 208.28 148.59))
  (no_connect (at 208.28 146.05))

  (wire (pts (xy 168.91 67.31) (xy 182.88 67.31))
    (stroke (width 0) (type default))
  )
  (wire (pts (xy 214.63 62.23) (xy 214.63 102.87))
    (stroke (width 0) (type default))
  )
  (wire (pts (xy 214.63 166.37) (xy 208.28 166.37))
    (stroke (width 0) (type default))
  )
  (wire (pts (xy 176.53 125.73) (xy 176.53 133.35))
    (stroke (width 0) (type default))
  )
  (wire (pts (xy 182.88 255.27) (xy 168.91 255.27))
    (stroke (width 0) (type default))
  )
  (wire (pts (xy 168.91 49.53) (xy 182.88 49.53))
    (stroke (width 0) (type default))
  )
  (wire (pts (xy 208.28 52.07) (xy 222.25 52.07))
    (stroke (width 0) (type default))
  )
  (wire (pts (xy 208.28 168.91) (xy 222.25 168.91))
    (stroke (width 0) (type default))
  )
  (wire (pts (xy 222.25 163.83) (xy 208.28 163.83))
    (stroke (width 0) (type default))
  )
  (wire (pts (xy 176.53 118.11) (xy 176.53 125.73))
    (stroke (width 0) (type default))
  )
  (wire (pts (xy 182.88 214.63) (xy 168.91 214.63))
    (stroke (width 0) (type default))
  )
  (wire (pts (xy 214.63 54.61) (xy 208.28 54.61))
    (stroke (width 0) (type default))
  )
  (wire (pts (xy 214.63 62.23) (xy 208.28 62.23))
    (stroke (width 0) (type default))
  )
  (wire (pts (xy 222.25 72.39) (xy 208.28 72.39))
    (stroke (width 0) (type default))
  )
  (wire (pts (xy 176.53 257.81) (xy 176.53 265.43))
    (stroke (width 0) (type default))
  )
  (wire (pts (xy 214.63 166.37) (xy 214.63 179.07))
    (stroke (width 0) (type default))
  )
  (wire (pts (xy 222.25 207.01) (xy 208.28 207.01))
    (stroke (width 0) (type default))
  )
  (wire (pts (xy 208.28 107.95) (xy 222.25 107.95))
    (stroke (width 0) (type default))
  )
  (wire (pts (xy 182.88 64.77) (xy 168.91 64.77))
    (stroke (width 0) (type default))
  )
  (wire (pts (xy 182.88 222.25) (xy 168.91 222.25))
    (stroke (width 0) (type default))
  )
  (wire (pts (xy 182.88 240.03) (xy 168.91 240.03))
    (stroke (width 0) (type default))
  )
  (wire (pts (xy 182.88 130.81) (xy 168.91 130.81))
    (stroke (width 0) (type default))
  )
  (wire (pts (xy 208.28 209.55) (xy 222.25 209.55))
    (stroke (width 0) (type default))
  )
  (wire (pts (xy 176.53 250.19) (xy 176.53 257.81))
    (stroke (width 0) (type default))
  )
  (wire (pts (xy 168.91 245.11) (xy 182.88 245.11))
    (stroke (width 0) (type default))
  )
  (wire (pts (xy 182.88 146.05) (xy 168.91 146.05))
    (stroke (width 0) (type default))
  )
  (wire (pts (xy 168.91 237.49) (xy 182.88 237.49))
    (stroke (width 0) (type default))
  )
  (wire (pts (xy 214.63 46.99) (xy 208.28 46.99))
    (stroke (width 0) (type default))
  )
  (wire (pts (xy 214.63 242.57) (xy 208.28 242.57))
    (stroke (width 0) (type default))
  )
  (wire (pts (xy 222.25 115.57) (xy 208.28 115.57))
    (stroke (width 0) (type default))
  )
  (wire (pts (xy 182.88 72.39) (xy 168.91 72.39))
    (stroke (width 0) (type default))
  )
  (wire (pts (xy 222.25 199.39) (xy 208.28 199.39))
    (stroke (width 0) (type default))
  )
  (wire (pts (xy 222.25 57.15) (xy 208.28 57.15))
    (stroke (width 0) (type default))
  )
  (wire (pts (xy 208.28 128.27) (xy 222.25 128.27))
    (stroke (width 0) (type default))
  )
  (wire (pts (xy 214.63 212.09) (xy 214.63 219.71))
    (stroke (width 0) (type default))
  )
  (wire (pts (xy 182.88 179.07) (xy 168.91 179.07))
    (stroke (width 0) (type default))
  )
  (wire (pts (xy 182.88 199.39) (xy 168.91 199.39))
    (stroke (width 0) (type default))
  )
  (wire (pts (xy 208.28 161.29) (xy 222.25 161.29))
    (stroke (width 0) (type default))
  )
  (wire (pts (xy 182.88 140.97) (xy 168.91 140.97))
    (stroke (width 0) (type default))
  )
  (wire (pts (xy 208.28 260.35) (xy 222.25 260.35))
    (stroke (width 0) (type default))
  )
  (wire (pts (xy 168.91 161.29) (xy 182.88 161.29))
    (stroke (width 0) (type default))
  )
  (wire (pts (xy 222.25 156.21) (xy 208.28 156.21))
    (stroke (width 0) (type default))
  )
  (wire (pts (xy 182.88 39.37) (xy 168.91 39.37))
    (stroke (width 0) (type default))
  )
  (wire (pts (xy 182.88 120.65) (xy 168.91 120.65))
    (stroke (width 0) (type default))
  )
  (wire (pts (xy 222.25 181.61) (xy 208.28 181.61))
    (stroke (width 0) (type default))
  )
  (wire (pts (xy 214.63 219.71) (xy 214.63 227.33))
    (stroke (width 0) (type default))
  )
  (wire (pts (xy 214.63 227.33) (xy 214.63 234.95))
    (stroke (width 0) (type default))
  )
  (wire (pts (xy 214.63 179.07) (xy 214.63 212.09))
    (stroke (width 0) (type default))
  )
  (wire (pts (xy 168.91 59.69) (xy 182.88 59.69))
    (stroke (width 0) (type default))
  )
  (wire (pts (xy 222.25 123.19) (xy 208.28 123.19))
    (stroke (width 0) (type default))
  )
  (wire (pts (xy 182.88 107.95) (xy 168.91 107.95))
    (stroke (width 0) (type default))
  )
  (wire (pts (xy 217.17 232.41) (xy 208.28 232.41))
    (stroke (width 0) (type default))
  )
  (wire (pts (xy 176.53 166.37) (xy 176.53 189.23))
    (stroke (width 0) (type default))
  )
  (wire (pts (xy 182.88 163.83) (xy 168.91 163.83))
    (stroke (width 0) (type default))
  )
  (wire (pts (xy 222.25 255.27) (xy 208.28 255.27))
    (stroke (width 0) (type default))
  )
  (wire (pts (xy 168.91 252.73) (xy 182.88 252.73))
    (stroke (width 0) (type default))
  )
  (wire (pts (xy 168.91 224.79) (xy 182.88 224.79))
    (stroke (width 0) (type default))
  )
  (wire (pts (xy 168.91 217.17) (xy 182.88 217.17))
    (stroke (width 0) (type default))
  )
  (wire (pts (xy 168.91 52.07) (xy 182.88 52.07))
    (stroke (width 0) (type default))
  )
  (wire (pts (xy 222.25 113.03) (xy 208.28 113.03))
    (stroke (width 0) (type default))
  )
  (wire (pts (xy 214.63 102.87) (xy 214.63 120.65))
    (stroke (width 0) (type default))
  )
  (wire (pts (xy 214.63 179.07) (xy 208.28 179.07))
    (stroke (width 0) (type default))
  )
  (wire (pts (xy 222.25 97.79) (xy 208.28 97.79))
    (stroke (width 0) (type default))
  )
  (wire (pts (xy 168.91 135.89) (xy 182.88 135.89))
    (stroke (width 0) (type default))
  )
  (wire (pts (xy 168.91 209.55) (xy 182.88 209.55))
    (stroke (width 0) (type default))
  )
  (wire (pts (xy 182.88 196.85) (xy 168.91 196.85))
    (stroke (width 0) (type default))
  )
  (wire (pts (xy 182.88 262.89) (xy 168.91 262.89))
    (stroke (width 0) (type default))
  )
  (wire (pts (xy 176.53 69.85) (xy 176.53 110.49))
    (stroke (width 0) (type default))
  )
  (wire (pts (xy 222.25 204.47) (xy 208.28 204.47))
    (stroke (width 0) (type default))
  )
  (wire (pts (xy 222.25 118.11) (xy 208.28 118.11))
    (stroke (width 0) (type default))
  )
  (wire (pts (xy 222.25 240.03) (xy 208.28 240.03))
    (stroke (width 0) (type default))
  )
  (wire (pts (xy 222.25 41.91) (xy 208.28 41.91))
    (stroke (width 0) (type default))
  )
  (wire (pts (xy 208.28 120.65) (xy 214.63 120.65))
    (stroke (width 0) (type default))
  )
  (wire (pts (xy 182.88 57.15) (xy 168.91 57.15))
    (stroke (width 0) (type default))
  )
  (wire (pts (xy 222.25 133.35) (xy 208.28 133.35))
    (stroke (width 0) (type default))
  )
  (wire (pts (xy 182.88 171.45) (xy 168.91 171.45))
    (stroke (width 0) (type default))
  )
  (wire (pts (xy 182.88 250.19) (xy 176.53 250.19))
    (stroke (width 0) (type default))
  )
  (wire (pts (xy 214.63 234.95) (xy 208.28 234.95))
    (stroke (width 0) (type default))
  )
  (wire (pts (xy 182.88 133.35) (xy 176.53 133.35))
    (stroke (width 0) (type default))
  )
  (wire (pts (xy 182.88 156.21) (xy 168.91 156.21))
    (stroke (width 0) (type default))
  )
  (wire (pts (xy 176.53 242.57) (xy 176.53 250.19))
    (stroke (width 0) (type default))
  )
  (wire (pts (xy 222.25 173.99) (xy 208.28 173.99))
    (stroke (width 0) (type default))
  )
  (wire (pts (xy 208.28 135.89) (xy 222.25 135.89))
    (stroke (width 0) (type default))
  )
  (wire (pts (xy 182.88 204.47) (xy 168.91 204.47))
    (stroke (width 0) (type default))
  )
  (wire (pts (xy 222.25 222.25) (xy 208.28 222.25))
    (stroke (width 0) (type default))
  )
  (wire (pts (xy 182.88 105.41) (xy 168.91 105.41))
    (stroke (width 0) (type default))
  )
  (wire (pts (xy 182.88 128.27) (xy 168.91 128.27))
    (stroke (width 0) (type default))
  )
  (wire (pts (xy 168.91 85.09) (xy 182.88 85.09))
    (stroke (width 0) (type default))
  )
  (wire (pts (xy 208.28 44.45) (xy 222.25 44.45))
    (stroke (width 0) (type default))
  )
  (wire (pts (xy 168.91 143.51) (xy 182.88 143.51))
    (stroke (width 0) (type default))
  )
  (wire (pts (xy 182.88 219.71) (xy 168.91 219.71))
    (stroke (width 0) (type default))
  )
  (wire (pts (xy 182.88 232.41) (xy 168.91 232.41))
    (stroke (width 0) (type default))
  )
  (wire (pts (xy 222.25 125.73) (xy 208.28 125.73))
    (stroke (width 0) (type default))
  )
  (wire (pts (xy 208.28 49.53) (xy 222.25 49.53))
    (stroke (width 0) (type default))
  )
  (wire (pts (xy 176.53 46.99) (xy 176.53 44.45))
    (stroke (width 0) (type default))
  )
  (wire (pts (xy 222.25 64.77) (xy 208.28 64.77))
    (stroke (width 0) (type default))
  )
  (wire (pts (xy 208.28 92.71) (xy 222.25 92.71))
    (stroke (width 0) (type default))
  )
  (wire (pts (xy 222.25 69.85) (xy 208.28 69.85))
    (stroke (width 0) (type default))
  )
  (wire (pts (xy 182.88 82.55) (xy 168.91 82.55))
    (stroke (width 0) (type default))
  )
  (wire (pts (xy 182.88 97.79) (xy 168.91 97.79))
    (stroke (width 0) (type default))
  )
  (wire (pts (xy 222.25 196.85) (xy 208.28 196.85))
    (stroke (width 0) (type default))
  )
  (wire (pts (xy 182.88 138.43) (xy 168.91 138.43))
    (stroke (width 0) (type default))
  )
  (wire (pts (xy 182.88 123.19) (xy 168.91 123.19))
    (stroke (width 0) (type default))
  )
  (wire (pts (xy 208.28 59.69) (xy 222.25 59.69))
    (stroke (width 0) (type default))
  )
  (wire (pts (xy 182.88 115.57) (xy 168.91 115.57))
    (stroke (width 0) (type default))
  )
  (wire (pts (xy 182.88 189.23) (xy 176.53 189.23))
    (stroke (width 0) (type default))
  )
  (wire (pts (xy 168.91 100.33) (xy 182.88 100.33))
    (stroke (width 0) (type default))
  )
  (wire (pts (xy 182.88 166.37) (xy 176.53 166.37))
    (stroke (width 0) (type default))
  )
  (wire (pts (xy 214.63 250.19) (xy 208.28 250.19))
    (stroke (width 0) (type default))
  )
  (wire (pts (xy 214.63 120.65) (xy 214.63 143.51))
    (stroke (width 0) (type default))
  )
  (wire (pts (xy 182.88 247.65) (xy 168.91 247.65))
    (stroke (width 0) (type default))
  )
  (wire (pts (xy 311.15 81.28) (xy 317.5 81.28))
    (stroke (width 0) (type default))
  )
  (wire (pts (xy 176.53 234.95) (xy 176.53 242.57))
    (stroke (width 0) (type default))
  )
  (wire (pts (xy 182.88 234.95) (xy 176.53 234.95))
    (stroke (width 0) (type default))
  )
  (wire (pts (xy 214.63 265.43) (xy 214.63 270.51))
    (stroke (width 0) (type default))
  )
  (wire (pts (xy 182.88 62.23) (xy 168.91 62.23))
    (stroke (width 0) (type default))
  )
  (wire (pts (xy 168.91 176.53) (xy 182.88 176.53))
    (stroke (width 0) (type default))
  )
  (wire (pts (xy 222.25 214.63) (xy 208.28 214.63))
    (stroke (width 0) (type default))
  )
  (wire (pts (xy 208.28 85.09) (xy 222.25 85.09))
    (stroke (width 0) (type default))
  )
  (wire (pts (xy 222.25 110.49) (xy 208.28 110.49))
    (stroke (width 0) (type default))
  )
  (wire (pts (xy 208.28 245.11) (xy 222.25 245.11))
    (stroke (width 0) (type default))
  )
  (wire (pts (xy 208.28 237.49) (xy 222.25 237.49))
    (stroke (width 0) (type default))
  )
  (wire (pts (xy 168.91 201.93) (xy 182.88 201.93))
    (stroke (width 0) (type default))
  )
  (wire (pts (xy 214.63 242.57) (xy 214.63 250.19))
    (stroke (width 0) (type default))
  )
  (wire (pts (xy 222.25 189.23) (xy 208.28 189.23))
    (stroke (width 0) (type default))
  )
  (wire (pts (xy 222.25 171.45) (xy 208.28 171.45))
    (stroke (width 0) (type default))
  )
  (wire (pts (xy 176.53 44.45) (xy 182.88 44.45))
    (stroke (width 0) (type default))
  )
  (wire (pts (xy 182.88 186.69) (xy 168.91 186.69))
    (stroke (width 0) (type default))
  )
  (wire (pts (xy 176.53 110.49) (xy 176.53 118.11))
    (stroke (width 0) (type default))
  )
  (wire (pts (xy 182.88 110.49) (xy 176.53 110.49))
    (stroke (width 0) (type default))
  )
  (wire (pts (xy 222.25 90.17) (xy 208.28 90.17))
    (stroke (width 0) (type default))
  )
  (wire (pts (xy 182.88 46.99) (xy 176.53 46.99))
    (stroke (width 0) (type default))
  )
  (wire (pts (xy 222.25 105.41) (xy 208.28 105.41))
    (stroke (width 0) (type default))
  )
  (wire (pts (xy 222.25 138.43) (xy 208.28 138.43))
    (stroke (width 0) (type default))
  )
  (wire (pts (xy 214.63 227.33) (xy 208.28 227.33))
    (stroke (width 0) (type default))
  )
  (wire (pts (xy 217.17 229.87) (xy 208.28 229.87))
    (stroke (width 0) (type default))
  )
  (wire (pts (xy 222.25 186.69) (xy 208.28 186.69))
    (stroke (width 0) (type default))
  )
  (wire (pts (xy 182.88 54.61) (xy 168.91 54.61))
    (stroke (width 0) (type default))
  )
  (wire (pts (xy 182.88 158.75) (xy 168.91 158.75))
    (stroke (width 0) (type default))
  )
  (wire (pts (xy 214.63 257.81) (xy 214.63 265.43))
    (stroke (width 0) (type default))
  )
  (wire (pts (xy 182.88 87.63) (xy 168.91 87.63))
    (stroke (width 0) (type default))
  )
  (wire (pts (xy 208.28 224.79) (xy 222.25 224.79))
    (stroke (width 0) (type default))
  )
  (wire (pts (xy 176.53 133.35) (xy 176.53 166.37))
    (stroke (width 0) (type default))
  )
  (wire (pts (xy 214.63 102.87) (xy 208.28 102.87))
    (stroke (width 0) (type default))
  )
  (wire (pts (xy 214.63 54.61) (xy 214.63 62.23))
    (stroke (width 0) (type default))
  )
  (wire (pts (xy 322.58 81.28) (xy 326.39 81.28))
    (stroke (width 0) (type default))
  )
  (wire (pts (xy 222.25 158.75) (xy 208.28 158.75))
    (stroke (width 0) (type default))
  )
  (wire (pts (xy 214.63 250.19) (xy 214.63 257.81))
    (stroke (width 0) (type default))
  )
  (wire (pts (xy 182.88 148.59) (xy 168.91 148.59))
    (stroke (width 0) (type default))
  )
  (wire (pts (xy 208.28 217.17) (xy 222.25 217.17))
    (stroke (width 0) (type default))
  )
  (wire (pts (xy 182.88 265.43) (xy 176.53 265.43))
    (stroke (width 0) (type default))
  )
  (wire (pts (xy 222.25 95.25) (xy 208.28 95.25))
    (stroke (width 0) (type default))
  )
  (wire (pts (xy 168.91 260.35) (xy 182.88 260.35))
    (stroke (width 0) (type default))
  )
  (wire (pts (xy 182.88 90.17) (xy 168.91 90.17))
    (stroke (width 0) (type default))
  )
  (wire (pts (xy 222.25 247.65) (xy 208.28 247.65))
    (stroke (width 0) (type default))
  )
  (wire (pts (xy 214.63 46.99) (xy 214.63 54.61))
    (stroke (width 0) (type default))
  )
  (wire (pts (xy 222.25 130.81) (xy 208.28 130.81))
    (stroke (width 0) (type default))
  )
  (wire (pts (xy 182.88 173.99) (xy 168.91 173.99))
    (stroke (width 0) (type default))
  )
  (wire (pts (xy 182.88 207.01) (xy 168.91 207.01))
    (stroke (width 0) (type default))
  )
  (wire (pts (xy 208.28 252.73) (xy 222.25 252.73))
    (stroke (width 0) (type default))
  )
  (wire (pts (xy 182.88 69.85) (xy 176.53 69.85))
    (stroke (width 0) (type default))
  )
  (wire (pts (xy 208.28 176.53) (xy 222.25 176.53))
    (stroke (width 0) (type default))
  )
  (wire (pts (xy 176.53 46.99) (xy 176.53 69.85))
    (stroke (width 0) (type default))
  )
  (wire (pts (xy 168.91 113.03) (xy 182.88 113.03))
    (stroke (width 0) (type default))
  )
  (wire (pts (xy 176.53 189.23) (xy 176.53 234.95))
    (stroke (width 0) (type default))
  )
  (wire (pts (xy 182.88 181.61) (xy 168.91 181.61))
    (stroke (width 0) (type default))
  )
  (wire (pts (xy 214.63 234.95) (xy 214.63 242.57))
    (stroke (width 0) (type default))
  )
  (wire (pts (xy 182.88 80.01) (xy 168.91 80.01))
    (stroke (width 0) (type default))
  )
  (wire (pts (xy 208.28 100.33) (xy 222.25 100.33))
    (stroke (width 0) (type default))
  )
  (wire (pts (xy 182.88 229.87) (xy 168.91 229.87))
    (stroke (width 0) (type default))
  )
  (wire (pts (xy 222.25 262.89) (xy 208.28 262.89))
    (stroke (width 0) (type default))
  )
  (wire (pts (xy 222.25 87.63) (xy 208.28 87.63))
    (stroke (width 0) (type default))
  )
  (wire (pts (xy 222.25 39.37) (xy 208.28 39.37))
    (stroke (width 0) (type default))
  )
  (wire (pts (xy 222.25 80.01) (xy 208.28 80.01))
    (stroke (width 0) (type default))
  )
  (wire (pts (xy 182.88 41.91) (xy 168.91 41.91))
    (stroke (width 0) (type default))
  )
  (wire (pts (xy 208.28 184.15) (xy 222.25 184.15))
    (stroke (width 0) (type default))
  )
  (wire (pts (xy 214.63 257.81) (xy 208.28 257.81))
    (stroke (width 0) (type default))
  )
  (wire (pts (xy 222.25 140.97) (xy 208.28 140.97))
    (stroke (width 0) (type default))
  )
  (wire (pts (xy 214.63 212.09) (xy 208.28 212.09))
    (stroke (width 0) (type default))
  )
  (wire (pts (xy 214.63 219.71) (xy 208.28 219.71))
    (stroke (width 0) (type default))
  )
  (wire (pts (xy 168.91 168.91) (xy 182.88 168.91))
    (stroke (width 0) (type default))
  )
  (wire (pts (xy 182.88 95.25) (xy 168.91 95.25))
    (stroke (width 0) (type default))
  )
  (wire (pts (xy 208.28 143.51) (xy 214.63 143.51))
    (stroke (width 0) (type default))
  )
  (wire (pts (xy 182.88 227.33) (xy 168.91 227.33))
    (stroke (width 0) (type default))
  )
  (wire (pts (xy 208.28 67.31) (xy 222.25 67.31))
    (stroke (width 0) (type default))
  )
  (wire (pts (xy 182.88 125.73) (xy 176.53 125.73))
    (stroke (width 0) (type default))
  )
  (wire (pts (xy 222.25 82.55) (xy 208.28 82.55))
    (stroke (width 0) (type default))
  )
  (wire (pts (xy 176.53 265.43) (xy 176.53 270.51))
    (stroke (width 0) (type default))
  )
  (wire (pts (xy 182.88 212.09) (xy 168.91 212.09))
    (stroke (width 0) (type default))
  )
  (wire (pts (xy 182.88 102.87) (xy 168.91 102.87))
    (stroke (width 0) (type default))
  )
  (wire (pts (xy 168.91 184.15) (xy 182.88 184.15))
    (stroke (width 0) (type default))
  )
  (wire (pts (xy 168.91 92.71) (xy 182.88 92.71))
    (stroke (width 0) (type default))
  )
  (wire (pts (xy 214.63 143.51) (xy 214.63 166.37))
    (stroke (width 0) (type default))
  )
  (wire (pts (xy 182.88 242.57) (xy 176.53 242.57))
    (stroke (width 0) (type default))
  )
  (wire (pts (xy 182.88 118.11) (xy 176.53 118.11))
    (stroke (width 0) (type default))
  )
  (wire (pts (xy 214.63 265.43) (xy 208.28 265.43))
    (stroke (width 0) (type default))
  )
  (wire (pts (xy 182.88 257.81) (xy 176.53 257.81))
    (stroke (width 0) (type default))
  )
  (wire (pts (xy 208.28 201.93) (xy 222.25 201.93))
    (stroke (width 0) (type default))
  )

  (text "Edge connector" (at 177.8 26.67 0)
    (effects (font (size 2.9972 2.9972)) (justify left bottom))
  )

  (global_label "CLK_PCIE_x4_DP" (shape input) (at 217.17 229.87 0) (fields_autoplaced)
    (effects (font (size 1.27 1.27)) (justify left))
    (property "Intersheetrefs" "${INTERSHEET_REFS}" (at -10.16 0.635 0)
      (effects (font (size 1.27 1.27)) hide)
    )
  )
  (global_label "ESPI_IO0" (shape input) (at 222.25 90.17 0) (fields_autoplaced)
    (effects (font (size 1.27 1.27)) (justify left))
    (property "Intersheetrefs" "${INTERSHEET_REFS}" (at -9.525 0.635 0)
      (effects (font (size 1.27 1.27)) hide)
    )
  )
  (global_label "I3C[1]_SDA_1V0" (shape input) (at 168.91 57.15 180) (fields_autoplaced)
    (effects (font (size 1.27 1.27)) (justify right))
    (property "Intersheetrefs" "${INTERSHEET_REFS}" (at 0.635 0.635 0)
      (effects (font (size 1.27 1.27)) hide)
    )
  )
  (global_label "ESPI_IO1" (shape input) (at 222.25 92.71 0) (fields_autoplaced)
    (effects (font (size 1.27 1.27)) (justify left))
    (property "Intersheetrefs" "${INTERSHEET_REFS}" (at -9.525 0.635 0)
      (effects (font (size 1.27 1.27)) hide)
    )
  )
  (global_label "I2C[10]_SDA" (shape input) (at 168.91 163.83 180) (fields_autoplaced)
    (effects (font (size 1.27 1.27)) (justify right))
    (property "Intersheetrefs" "${INTERSHEET_REFS}" (at 0.635 0.635 0)
      (effects (font (size 1.27 1.27)) hide)
    )
  )
  (global_label "ESPI_ALERT_N" (shape input) (at 222.25 85.09 0) (fields_autoplaced)
    (effects (font (size 1.27 1.27)) (justify left))
    (property "Intersheetrefs" "${INTERSHEET_REFS}" (at -9.525 0.635 0)
      (effects (font (size 1.27 1.27)) hide)
    )
  )
  (global_label "QSPI1_CLK" (shape input) (at 222.25 196.85 0) (fields_autoplaced)
    (effects (font (size 1.27 1.27)) (justify left))
    (property "Intersheetrefs" "${INTERSHEET_REFS}" (at -9.525 0.635 0)
      (effects (font (size 1.27 1.27)) hide)
    )
  )
  (global_label "QSPI0_D0" (shape input) (at 222.25 110.49 0) (fields_autoplaced)
    (effects (font (size 1.27 1.27)) (justify left))
    (property "Intersheetrefs" "${INTERSHEET_REFS}" (at -9.525 0.635 0)
      (effects (font (size 1.27 1.27)) hide)
    )
  )
  (global_label "HPM_STBY_RST_N" (shape input) (at 168.91 204.47 180) (fields_autoplaced)
    (effects (font (size 1.27 1.27)) (justify right))
    (property "Intersheetrefs" "${INTERSHEET_REFS}" (at 0.635 0.635 0)
      (effects (font (size 1.27 1.27)) hide)
    )
  )
  (global_label "NCSI_RXD1" (shape input) (at 222.25 140.97 0) (fields_autoplaced)
    (effects (font (size 1.27 1.27)) (justify left))
    (property "Intersheetrefs" "${INTERSHEET_REFS}" (at -9.525 0.635 0)
      (effects (font (size 1.27 1.27)) hide)
    )
  )
  (global_label "I3C[2]_SCL_1V0" (shape input) (at 168.91 59.69 180) (fields_autoplaced)
    (effects (font (size 1.27 1.27)) (justify right))
    (property "Intersheetrefs" "${INTERSHEET_REFS}" (at 0.635 0.635 0)
      (effects (font (size 1.27 1.27)) hide)
    )
  )
  (global_label "NCSI_RXER" (shape input) (at 222.25 135.89 0) (fields_autoplaced)
    (effects (font (size 1.27 1.27)) (justify left))
    (property "Intersheetrefs" "${INTERSHEET_REFS}" (at -9.525 0.635 0)
      (effects (font (size 1.27 1.27)) hide)
    )
  )
  (global_label "NCSI_TXEN" (shape input) (at 222.25 128.27 0) (fields_autoplaced)
    (effects (font (size 1.27 1.27)) (justify left))
    (property "Intersheetrefs" "${INTERSHEET_REFS}" (at -9.525 0.635 0)
      (effects (font (size 1.27 1.27)) hide)
    )
  )
  (global_label "NCSI_CRS_DV" (shape input) (at 222.25 125.73 0) (fields_autoplaced)
    (effects (font (size 1.27 1.27)) (justify left))
    (property "Intersheetrefs" "${INTERSHEET_REFS}" (at -9.525 0.635 0)
      (effects (font (size 1.27 1.27)) hide)
    )
  )
  (global_label "I2C[12]_SDA" (shape input) (at 168.91 186.69 180) (fields_autoplaced)
    (effects (font (size 1.27 1.27)) (justify right))
    (property "Intersheetrefs" "${INTERSHEET_REFS}" (at 0.635 0.635 0)
      (effects (font (size 1.27 1.27)) hide)
    )
  )
  (global_label "UART1_SCM_RX" (shape input) (at 222.25 52.07 0) (fields_autoplaced)
    (effects (font (size 1.27 1.27)) (justify left))
    (property "Intersheetrefs" "${INTERSHEET_REFS}" (at -9.525 0.635 0)
      (effects (font (size 1.27 1.27)) hide)
    )
  )
  (global_label "P12V_AUX" (shape input) (at 222.25 39.37 0) (fields_autoplaced)
    (effects (font (size 1.27 1.27)) (justify left))
    (property "Intersheetrefs" "${INTERSHEET_REFS}" (at -9.525 0.635 0)
      (effects (font (size 1.27 1.27)) hide)
    )
  )
  (global_label "I2C[3]_SDA" (shape input) (at 168.91 97.79 180) (fields_autoplaced)
    (effects (font (size 1.27 1.27)) (justify right))
    (property "Intersheetrefs" "${INTERSHEET_REFS}" (at 0.635 0.635 0)
      (effects (font (size 1.27 1.27)) hide)
    )
  )
  (global_label "SGPIO1_LD" (shape input) (at 222.25 176.53 0) (fields_autoplaced)
    (effects (font (size 1.27 1.27)) (justify left))
    (property "Intersheetrefs" "${INTERSHEET_REFS}" (at -9.525 0.635 0)
      (effects (font (size 1.27 1.27)) hide)
    )
  )
  (global_label "CLK_100M_PCIE_DN" (shape input) (at 168.91 115.57 180) (fields_autoplaced)
    (effects (font (size 1.27 1.27)) (justify right))
    (property "Intersheetrefs" "${INTERSHEET_REFS}" (at 0.635 0.635 0)
      (effects (font (size 1.27 1.27)) hide)
    )
  )
  (global_label "I2C[5]_SDA" (shape input) (at 168.91 107.95 180) (fields_autoplaced)
    (effects (font (size 1.27 1.27)) (justify right))
    (property "Intersheetrefs" "${INTERSHEET_REFS}" (at 0.635 0.635 0)
      (effects (font (size 1.27 1.27)) hide)
    )
  )
  (global_label "I2C[6]_SCL" (shape input) (at 168.91 135.89 180) (fields_autoplaced)
    (effects (font (size 1.27 1.27)) (justify right))
    (property "Intersheetrefs" "${INTERSHEET_REFS}" (at 0.635 0.635 0)
      (effects (font (size 1.27 1.27)) hide)
    )
  )
  (global_label "SPARE0" (shape input) (at 168.91 227.33 180) (fields_autoplaced)
    (effects (font (size 1.27 1.27)) (justify right))
    (property "Intersheetrefs" "${INTERSHEET_REFS}" (at 0.635 0.635 0)
      (effects (font (size 1.27 1.27)) hide)
    )
  )
  (global_label "QSPI0_D2" (shape input) (at 222.25 115.57 0) (fields_autoplaced)
    (effects (font (size 1.27 1.27)) (justify left))
    (property "Intersheetrefs" "${INTERSHEET_REFS}" (at -9.525 0.635 0)
      (effects (font (size 1.27 1.27)) hide)
    )
  )
  (global_label "SPI0_CLK" (shape input) (at 222.25 64.77 0) (fields_autoplaced)
    (effects (font (size 1.27 1.27)) (justify left))
    (property "Intersheetrefs" "${INTERSHEET_REFS}" (at -9.525 0.635 0)
      (effects (font (size 1.27 1.27)) hide)
    )
  )
  (global_label "VIRTUAL_RESEAT" (shape input) (at 168.91 72.39 180) (fields_autoplaced)
    (effects (font (size 1.27 1.27)) (justify right))
    (property "Intersheetrefs" "${INTERSHEET_REFS}" (at 0.635 0.635 0)
      (effects (font (size 1.27 1.27)) hide)
    )
  )
  (global_label "QSPI1_CS0_N" (shape input) (at 222.25 199.39 0) (fields_autoplaced)
    (effects (font (size 1.27 1.27)) (justify left))
    (property "Intersheetrefs" "${INTERSHEET_REFS}" (at -9.525 0.635 0)
      (effects (font (size 1.27 1.27)) hide)
    )
  )
  (global_label "PCIE_HPM_RX1_N" (shape input) (at 168.91 247.65 180) (fields_autoplaced)
    (effects (font (size 1.27 1.27)) (justify right))
    (property "Intersheetrefs" "${INTERSHEET_REFS}" (at 0.635 0.635 0)
      (effects (font (size 1.27 1.27)) hide)
    )
  )
  (global_label "HPM_STBY_RDY" (shape input) (at 168.91 199.39 180) (fields_autoplaced)
    (effects (font (size 1.27 1.27)) (justify right))
    (property "Intersheetrefs" "${INTERSHEET_REFS}" (at 0.635 0.635 0)
      (effects (font (size 1.27 1.27)) hide)
    )
  )
  (global_label "I3C[1]_SCL_1V0" (shape input) (at 168.91 54.61 180) (fields_autoplaced)
    (effects (font (size 1.27 1.27)) (justify right))
    (property "Intersheetrefs" "${INTERSHEET_REFS}" (at 0.635 0.635 0)
      (effects (font (size 1.27 1.27)) hide)
    )
  )
  (global_label "I2C[3]_SCL" (shape input) (at 168.91 95.25 180) (fields_autoplaced)
    (effects (font (size 1.27 1.27)) (justify right))
    (property "Intersheetrefs" "${INTERSHEET_REFS}" (at 0.635 0.635 0)
      (effects (font (size 1.27 1.27)) hide)
    )
  )
  (global_label "PCIE_HPM_RX2_N" (shape input) (at 168.91 255.27 180) (fields_autoplaced)
    (effects (font (size 1.27 1.27)) (justify right))
    (property "Intersheetrefs" "${INTERSHEET_REFS}" (at 0.635 0.635 0)
      (effects (font (size 1.27 1.27)) hide)
    )
  )
  (global_label "RoT_CPU_RST_N" (shape input) (at 168.91 222.25 180) (fields_autoplaced)
    (effects (font (size 1.27 1.27)) (justify right))
    (property "Intersheetrefs" "${INTERSHEET_REFS}" (at 0.635 0.635 0)
      (effects (font (size 1.27 1.27)) hide)
    )
  )
  (global_label "RST_PLTRST_BUF_N" (shape input) (at 168.91 217.17 180) (fields_autoplaced)
    (effects (font (size 1.27 1.27)) (justify right))
    (property "Intersheetrefs" "${INTERSHEET_REFS}" (at 0.635 0.635 0)
      (effects (font (size 1.27 1.27)) hide)
    )
  )
  (global_label "I2C[2]_SDA" (shape input) (at 168.91 92.71 180) (fields_autoplaced)
    (effects (font (size 1.27 1.27)) (justify right))
    (property "Intersheetrefs" "${INTERSHEET_REFS}" (at 0.635 0.635 0)
      (effects (font (size 1.27 1.27)) hide)
    )
  )
  (global_label "3V0_BAT" (shape input) (at 222.25 186.69 0) (fields_autoplaced)
    (effects (font (size 1.27 1.27)) (justify left))
    (property "Intersheetrefs" "${INTERSHEET_REFS}" (at -9.525 0.635 0)
      (effects (font (size 1.27 1.27)) hide)
    )
  )
  (global_label "PCIE_BMC_TX_DN" (shape input) (at 168.91 123.19 180) (fields_autoplaced)
    (effects (font (size 1.27 1.27)) (justify right))
    (property "Intersheetrefs" "${INTERSHEET_REFS}" (at 0.635 0.635 0)
      (effects (font (size 1.27 1.27)) hide)
    )
  )
  (global_label "I2C[0]_SCL" (shape input) (at 168.91 80.01 180) (fields_autoplaced)
    (effects (font (size 1.27 1.27)) (justify right))
    (property "Intersheetrefs" "${INTERSHEET_REFS}" (at 0.635 0.635 0)
      (effects (font (size 1.27 1.27)) hide)
    )
  )
  (global_label "PCIE_HPM_TX0_N" (shape input) (at 222.25 240.03 0) (fields_autoplaced)
    (effects (font (size 1.27 1.27)) (justify left))
    (property "Intersheetrefs" "${INTERSHEET_REFS}" (at -9.525 0.635 0)
      (effects (font (size 1.27 1.27)) hide)
    )
  )
  (global_label "SGPIO0_LD" (shape input) (at 222.25 163.83 0) (fields_autoplaced)
    (effects (font (size 1.27 1.27)) (justify left))
    (property "Intersheetrefs" "${INTERSHEET_REFS}" (at -9.525 0.635 0)
      (effects (font (size 1.27 1.27)) hide)
    )
  )
  (global_label "QSPI1_D0" (shape input) (at 222.25 201.93 0) (fields_autoplaced)
    (effects (font (size 1.27 1.27)) (justify left))
    (property "Intersheetrefs" "${INTERSHEET_REFS}" (at -9.525 0.635 0)
      (effects (font (size 1.27 1.27)) hide)
    )
  )
  (global_label "DBP_PRDY_N" (shape input) (at 168.91 214.63 180) (fields_autoplaced)
    (effects (font (size 1.27 1.27)) (justify right))
    (property "Intersheetrefs" "${INTERSHEET_REFS}" (at 0.635 0.635 0)
      (effects (font (size 1.27 1.27)) hide)
    )
  )
  (global_label "SGPIO0_CLK" (shape input) (at 222.25 158.75 0) (fields_autoplaced)
    (effects (font (size 1.27 1.27)) (justify left))
    (property "Intersheetrefs" "${INTERSHEET_REFS}" (at -9.525 0.635 0)
      (effects (font (size 1.27 1.27)) hide)
    )
  )
  (global_label "I2C[9]_SDA" (shape input) (at 168.91 158.75 180) (fields_autoplaced)
    (effects (font (size 1.27 1.27)) (justify right))
    (property "Intersheetrefs" "${INTERSHEET_REFS}" (at 0.635 0.635 0)
      (effects (font (size 1.27 1.27)) hide)
    )
  )
  (global_label "PCIE_HPM_TX2_N" (shape input) (at 222.25 255.27 0) (fields_autoplaced)
    (effects (font (size 1.27 1.27)) (justify left))
    (property "Intersheetrefs" "${INTERSHEET_REFS}" (at -9.525 0.635 0)
      (effects (font (size 1.27 1.27)) hide)
    )
  )
  (global_label "PCIE_HPM_RX0_P" (shape input) (at 168.91 237.49 180) (fields_autoplaced)
    (effects (font (size 1.27 1.27)) (justify right))
    (property "Intersheetrefs" "${INTERSHEET_REFS}" (at 0.635 0.635 0)
      (effects (font (size 1.27 1.27)) hide)
    )
  )
  (global_label "ESPI_IO3" (shape input) (at 222.25 97.79 0) (fields_autoplaced)
    (effects (font (size 1.27 1.27)) (justify left))
    (property "Intersheetrefs" "${INTERSHEET_REFS}" (at -9.525 0.635 0)
      (effects (font (size 1.27 1.27)) hide)
    )
  )
  (global_label "PCIE_HPM_TX3_P" (shape input) (at 222.25 260.35 0) (fields_autoplaced)
    (effects (font (size 1.27 1.27)) (justify left))
    (property "Intersheetrefs" "${INTERSHEET_REFS}" (at -9.525 0.635 0)
      (effects (font (size 1.27 1.27)) hide)
    )
  )
  (global_label "USB1_DN" (shape input) (at 222.25 224.79 0) (fields_autoplaced)
    (effects (font (size 1.27 1.27)) (justify left))
    (property "Intersheetrefs" "${INTERSHEET_REFS}" (at -9.525 0.635 0)
      (effects (font (size 1.27 1.27)) hide)
    )
  )
  (global_label "CLK_100M_PCIE_DP" (shape input) (at 168.91 113.03 180) (fields_autoplaced)
    (effects (font (size 1.27 1.27)) (justify right))
    (property "Intersheetrefs" "${INTERSHEET_REFS}" (at 0.635 0.635 0)
      (effects (font (size 1.27 1.27)) hide)
    )
  )
  (global_label "ESPI_CS1_N" (shape input) (at 222.25 100.33 0) (fields_autoplaced)
    (effects (font (size 1.27 1.27)) (justify left))
    (property "Intersheetrefs" "${INTERSHEET_REFS}" (at -9.525 0.635 0)
      (effects (font (size 1.27 1.27)) hide)
    )
  )
  (global_label "PCIE_HPM_RX0_N" (shape input) (at 168.91 240.03 180) (fields_autoplaced)
    (effects (font (size 1.27 1.27)) (justify right))
    (property "Intersheetrefs" "${INTERSHEET_REFS}" (at 0.635 0.635 0)
      (effects (font (size 1.27 1.27)) hide)
    )
  )
  (global_label "I2C[10]_SCL" (shape input) (at 168.91 161.29 180) (fields_autoplaced)
    (effects (font (size 1.27 1.27)) (justify right))
    (property "Intersheetrefs" "${INTERSHEET_REFS}" (at 0.635 0.635 0)
      (effects (font (size 1.27 1.27)) hide)
    )
  )
  (global_label "NCSI_CLK" (shape input) (at 222.25 123.19 0) (fields_autoplaced)
    (effects (font (size 1.27 1.27)) (justify left))
    (property "Intersheetrefs" "${INTERSHEET_REFS}" (at -9.525 0.635 0)
      (effects (font (size 1.27 1.27)) hide)
    )
  )
  (global_label "UART0_SCM_TX" (shape input) (at 222.25 57.15 0) (fields_autoplaced)
    (effects (font (size 1.27 1.27)) (justify left))
    (property "Intersheetrefs" "${INTERSHEET_REFS}" (at -9.525 0.635 0)
      (effects (font (size 1.27 1.27)) hide)
    )
  )
  (global_label "I2C[6]_SDA" (shape input) (at 168.91 138.43 180) (fields_autoplaced)
    (effects (font (size 1.27 1.27)) (justify right))
    (property "Intersheetrefs" "${INTERSHEET_REFS}" (at 0.635 0.635 0)
      (effects (font (size 1.27 1.27)) hide)
    )
  )
  (global_label "ESPI_CLK" (shape input) (at 222.25 80.01 0) (fields_autoplaced)
    (effects (font (size 1.27 1.27)) (justify left))
    (property "Intersheetrefs" "${INTERSHEET_REFS}" (at -9.525 0.635 0)
      (effects (font (size 1.27 1.27)) hide)
    )
  )
  (global_label "NCSI_TXD1" (shape input) (at 222.25 133.35 0) (fields_autoplaced)
    (effects (font (size 1.27 1.27)) (justify left))
    (property "Intersheetrefs" "${INTERSHEET_REFS}" (at -9.525 0.635 0)
      (effects (font (size 1.27 1.27)) hide)
    )
  )
  (global_label "SPI0_MISO" (shape input) (at 222.25 72.39 0) (fields_autoplaced)
    (effects (font (size 1.27 1.27)) (justify left))
    (property "Intersheetrefs" "${INTERSHEET_REFS}" (at -9.525 0.635 0)
      (effects (font (size 1.27 1.27)) hide)
    )
  )
  (global_label "USB2_DP" (shape input) (at 222.25 214.63 0) (fields_autoplaced)
    (effects (font (size 1.27 1.27)) (justify left))
    (property "Intersheetrefs" "${INTERSHEET_REFS}" (at -9.525 0.635 0)
      (effects (font (size 1.27 1.27)) hide)
    )
  )
  (global_label "CLK_PCIE_x4_DN" (shape input) (at 217.17 232.41 0) (fields_autoplaced)
    (effects (font (size 1.27 1.27)) (justify left))
    (property "Intersheetrefs" "${INTERSHEET_REFS}" (at -10.16 0.635 0)
      (effects (font (size 1.27 1.27)) hide)
    )
  )
  (global_label "I2C[9]_SCL" (shape input) (at 168.91 156.21 180) (fields_autoplaced)
    (effects (font (size 1.27 1.27)) (justify right))
    (property "Intersheetrefs" "${INTERSHEET_REFS}" (at 0.635 0.635 0)
      (effects (font (size 1.27 1.27)) hide)
    )
  )
  (global_label "I3C[3]_SCL_1V0" (shape input) (at 168.91 64.77 180) (fields_autoplaced)
    (effects (font (size 1.27 1.27)) (justify right))
    (property "Intersheetrefs" "${INTERSHEET_REFS}" (at 0.635 0.635 0)
      (effects (font (size 1.27 1.27)) hide)
    )
  )
  (global_label "PCIE_HPM_TX2_P" (shape input) (at 222.25 252.73 0) (fields_autoplaced)
    (effects (font (size 1.27 1.27)) (justify left))
    (property "Intersheetrefs" "${INTERSHEET_REFS}" (at -9.525 0.635 0)
      (effects (font (size 1.27 1.27)) hide)
    )
  )
  (global_label "I3C[0]_SDA_1V0" (shape input) (at 168.91 52.07 180) (fields_autoplaced)
    (effects (font (size 1.27 1.27)) (justify right))
    (property "Intersheetrefs" "${INTERSHEET_REFS}" (at 0.635 0.635 0)
      (effects (font (size 1.27 1.27)) hide)
    )
  )
  (global_label "ESPI_CS0_N" (shape input) (at 222.25 82.55 0) (fields_autoplaced)
    (effects (font (size 1.27 1.27)) (justify left))
    (property "Intersheetrefs" "${INTERSHEET_REFS}" (at -9.525 0.635 0)
      (effects (font (size 1.27 1.27)) hide)
    )
  )
  (global_label "SYS_PWRBTN_N" (shape input) (at 168.91 207.01 180) (fields_autoplaced)
    (effects (font (size 1.27 1.27)) (justify right))
    (property "Intersheetrefs" "${INTERSHEET_REFS}" (at 0.635 0.635 0)
      (effects (font (size 1.27 1.27)) hide)
    )
  )
  (global_label "JTAG_TDO" (shape input) (at 168.91 176.53 180) (fields_autoplaced)
    (effects (font (size 1.27 1.27)) (justify right))
    (property "Intersheetrefs" "${INTERSHEET_REFS}" (at 0.635 0.635 0)
      (effects (font (size 1.27 1.27)) hide)
    )
  )
  (global_label "JTAG_TDI" (shape input) (at 168.91 173.99 180) (fields_autoplaced)
    (effects (font (size 1.27 1.27)) (justify right))
    (property "Intersheetrefs" "${INTERSHEET_REFS}" (at 0.635 0.635 0)
      (effects (font (size 1.27 1.27)) hide)
    )
  )
  (global_label "I2C[8]_SDA" (shape input) (at 168.91 148.59 180) (fields_autoplaced)
    (effects (font (size 1.27 1.27)) (justify right))
    (property "Intersheetrefs" "${INTERSHEET_REFS}" (at 0.635 0.635 0)
      (effects (font (size 1.27 1.27)) hide)
    )
  )
  (global_label "I2C[5]_SCL" (shape input) (at 168.91 105.41 180) (fields_autoplaced)
    (effects (font (size 1.27 1.27)) (justify right))
    (property "Intersheetrefs" "${INTERSHEET_REFS}" (at 0.635 0.635 0)
      (effects (font (size 1.27 1.27)) hide)
    )
  )
  (global_label "PCIE_HPM_RX3_P" (shape input) (at 168.91 260.35 180) (fields_autoplaced)
    (effects (font (size 1.27 1.27)) (justify right))
    (property "Intersheetrefs" "${INTERSHEET_REFS}" (at 0.635 0.635 0)
      (effects (font (size 1.27 1.27)) hide)
    )
  )
  (global_label "SGPIO_RESET_N" (shape input) (at 222.25 181.61 0) (fields_autoplaced)
    (effects (font (size 1.27 1.27)) (justify left))
    (property "Intersheetrefs" "${INTERSHEET_REFS}" (at -9.525 0.635 0)
      (effects (font (size 1.27 1.27)) hide)
    )
  )
  (global_label "HPM_STBY_EN" (shape input) (at 168.91 201.93 180) (fields_autoplaced)
    (effects (font (size 1.27 1.27)) (justify right))
    (property "Intersheetrefs" "${INTERSHEET_REFS}" (at 0.635 0.635 0)
      (effects (font (size 1.27 1.27)) hide)
    )
  )
  (global_label "I2C[7]_SDA" (shape input) (at 168.91 143.51 180) (fields_autoplaced)
    (effects (font (size 1.27 1.27)) (justify right))
    (property "Intersheetrefs" "${INTERSHEET_REFS}" (at 0.635 0.635 0)
      (effects (font (size 1.27 1.27)) hide)
    )
  )
  (global_label "QSPI0_D1" (shape input) (at 222.25 113.03 0) (fields_autoplaced)
    (effects (font (size 1.27 1.27)) (justify left))
    (property "Intersheetrefs" "${INTERSHEET_REFS}" (at -9.525 0.635 0)
      (effects (font (size 1.27 1.27)) hide)
    )
  )
  (global_label "USB2_DN" (shape input) (at 222.25 217.17 0) (fields_autoplaced)
    (effects (font (size 1.27 1.27)) (justify left))
    (property "Intersheetrefs" "${INTERSHEET_REFS}" (at -9.525 0.635 0)
      (effects (font (size 1.27 1.27)) hide)
    )
  )
  (global_label "CHASI#" (shape input) (at 168.91 224.79 180) (fields_autoplaced)
    (effects (font (size 1.27 1.27)) (justify right))
    (property "Intersheetrefs" "${INTERSHEET_REFS}" (at 0.635 0.635 0)
      (effects (font (size 1.27 1.27)) hide)
    )
  )
  (global_label "SGPIO0_DI" (shape input) (at 222.25 161.29 0) (fields_autoplaced)
    (effects (font (size 1.27 1.27)) (justify left))
    (property "Intersheetrefs" "${INTERSHEET_REFS}" (at -9.525 0.635 0)
      (effects (font (size 1.27 1.27)) hide)
    )
  )
  (global_label "SGPIO1_CLK" (shape input) (at 222.25 171.45 0) (fields_autoplaced)
    (effects (font (size 1.27 1.27)) (justify left))
    (property "Intersheetrefs" "${INTERSHEET_REFS}" (at -9.525 0.635 0)
      (effects (font (size 1.27 1.27)) hide)
    )
  )
  (global_label "SGPIO1_CLK" (shape input) (at 311.15 81.28 180) (fields_autoplaced)
    (effects (font (size 1.27 1.27)) (justify right))
    (property "Intersheetrefs" "${INTERSHEET_REFS}" (at 47.625 -89.535 0)
      (effects (font (size 1.27 1.27)) hide)
    )
  )
  (global_label "PCIE_HPM_RX3_N" (shape input) (at 168.91 262.89 180) (fields_autoplaced)
    (effects (font (size 1.27 1.27)) (justify right))
    (property "Intersheetrefs" "${INTERSHEET_REFS}" (at 0.635 0.635 0)
      (effects (font (size 1.27 1.27)) hide)
    )
  )
  (global_label "DBP_PREQ_N" (shape input) (at 168.91 212.09 180) (fields_autoplaced)
    (effects (font (size 1.27 1.27)) (justify right))
    (property "Intersheetrefs" "${INTERSHEET_REFS}" (at 0.635 0.635 0)
      (effects (font (size 1.27 1.27)) hide)
    )
  )
  (global_label "QSPI0_CLK" (shape input) (at 222.25 105.41 0) (fields_autoplaced)
    (effects (font (size 1.27 1.27)) (justify left))
    (property "Intersheetrefs" "${INTERSHEET_REFS}" (at -9.525 0.635 0)
      (effects (font (size 1.27 1.27)) hide)
    )
  )
  (global_label "PRSNT0_N" (shape input) (at 222.25 44.45 0) (fields_autoplaced)
    (effects (font (size 1.27 1.27)) (justify left))
    (property "Intersheetrefs" "${INTERSHEET_REFS}" (at -9.525 0.635 0)
      (effects (font (size 1.27 1.27)) hide)
    )
  )
  (global_label "I2C[11]_SCL" (shape input) (at 168.91 179.07 180) (fields_autoplaced)
    (effects (font (size 1.27 1.27)) (justify right))
    (property "Intersheetrefs" "${INTERSHEET_REFS}" (at 0.635 0.635 0)
      (effects (font (size 1.27 1.27)) hide)
    )
  )
  (global_label "SGPIO_INTR_N" (shape input) (at 222.25 184.15 0) (fields_autoplaced)
    (effects (font (size 1.27 1.27)) (justify left))
    (property "Intersheetrefs" "${INTERSHEET_REFS}" (at -9.525 0.635 0)
      (effects (font (size 1.27 1.27)) hide)
    )
  )
  (global_label "PCIE_BMC_RX_DN" (shape input) (at 168.91 130.81 180) (fields_autoplaced)
    (effects (font (size 1.27 1.27)) (justify right))
    (property "Intersheetrefs" "${INTERSHEET_REFS}" (at 0.635 0.635 0)
      (effects (font (size 1.27 1.27)) hide)
    )
  )
  (global_label "USB1_DP" (shape input) (at 222.25 222.25 0) (fields_autoplaced)
    (effects (font (size 1.27 1.27)) (justify left))
    (property "Intersheetrefs" "${INTERSHEET_REFS}" (at -9.525 0.635 0)
      (effects (font (size 1.27 1.27)) hide)
    )
  )
  (global_label "PCIE_HPM_RX2_P" (shape input) (at 168.91 252.73 180) (fields_autoplaced)
    (effects (font (size 1.27 1.27)) (justify right))
    (property "Intersheetrefs" "${INTERSHEET_REFS}" (at 0.635 0.635 0)
      (effects (font (size 1.27 1.27)) hide)
    )
  )
  (global_label "QSPI0_CS1_N" (shape input) (at 222.25 189.23 0) (fields_autoplaced)
    (effects (font (size 1.27 1.27)) (justify left))
    (property "Intersheetrefs" "${INTERSHEET_REFS}" (at -9.525 0.635 0)
      (effects (font (size 1.27 1.27)) hide)
    )
  )
  (global_label "ESPI_IO2" (shape input) (at 222.25 95.25 0) (fields_autoplaced)
    (effects (font (size 1.27 1.27)) (justify left))
    (property "Intersheetrefs" "${INTERSHEET_REFS}" (at -9.525 0.635 0)
      (effects (font (size 1.27 1.27)) hide)
    )
  )
  (global_label "NCSI_TXD0" (shape input) (at 222.25 130.81 0) (fields_autoplaced)
    (effects (font (size 1.27 1.27)) (justify left))
    (property "Intersheetrefs" "${INTERSHEET_REFS}" (at -9.525 0.635 0)
      (effects (font (size 1.27 1.27)) hide)
    )
  )
  (global_label "P12V_AUX" (shape input) (at 168.91 39.37 180) (fields_autoplaced)
    (effects (font (size 1.27 1.27)) (justify right))
    (property "Intersheetrefs" "${INTERSHEET_REFS}" (at 0.635 0.635 0)
      (effects (font (size 1.27 1.27)) hide)
    )
  )
  (global_label "PCIE_HPM_TX0_P" (shape input) (at 222.25 237.49 0) (fields_autoplaced)
    (effects (font (size 1.27 1.27)) (justify left))
    (property "Intersheetrefs" "${INTERSHEET_REFS}" (at -9.525 0.635 0)
      (effects (font (size 1.27 1.27)) hide)
    )
  )
  (global_label "SPI0_MOSI" (shape input) (at 222.25 69.85 0) (fields_autoplaced)
    (effects (font (size 1.27 1.27)) (justify left))
    (property "Intersheetrefs" "${INTERSHEET_REFS}" (at -9.525 0.635 0)
      (effects (font (size 1.27 1.27)) hide)
    )
  )
  (global_label "ESPI_RESET_N" (shape input) (at 222.25 87.63 0) (fields_autoplaced)
    (effects (font (size 1.27 1.27)) (justify left))
    (property "Intersheetrefs" "${INTERSHEET_REFS}" (at -9.525 0.635 0)
      (effects (font (size 1.27 1.27)) hide)
    )
  )
  (global_label "PRSNT1_N" (shape input) (at 168.91 232.41 180) (fields_autoplaced)
    (effects (font (size 1.27 1.27)) (justify right))
    (property "Intersheetrefs" "${INTERSHEET_REFS}" (at 0.635 0.635 0)
      (effects (font (size 1.27 1.27)) hide)
    )
  )
  (global_label "QSPI0_CS0_N" (shape input) (at 222.25 107.95 0) (fields_autoplaced)
    (effects (font (size 1.27 1.27)) (justify left))
    (property "Intersheetrefs" "${INTERSHEET_REFS}" (at -9.525 0.635 0)
      (effects (font (size 1.27 1.27)) hide)
    )
  )
  (global_label "I2C[1]_SCL" (shape input) (at 168.91 85.09 180) (fields_autoplaced)
    (effects (font (size 1.27 1.27)) (justify right))
    (property "Intersheetrefs" "${INTERSHEET_REFS}" (at 0.635 0.635 0)
      (effects (font (size 1.27 1.27)) hide)
    )
  )
  (global_label "P12V_AUX" (shape input) (at 168.91 41.91 180) (fields_autoplaced)
    (effects (font (size 1.27 1.27)) (justify right))
    (property "Intersheetrefs" "${INTERSHEET_REFS}" (at 0.635 0.635 0)
      (effects (font (size 1.27 1.27)) hide)
    )
  )
  (global_label "UART1_SCM_TX" (shape input) (at 222.25 49.53 0) (fields_autoplaced)
    (effects (font (size 1.27 1.27)) (justify left))
    (property "Intersheetrefs" "${INTERSHEET_REFS}" (at -9.525 0.635 0)
      (effects (font (size 1.27 1.27)) hide)
    )
  )
  (global_label "I2C[4]_SDA" (shape input) (at 168.91 102.87 180) (fields_autoplaced)
    (effects (font (size 1.27 1.27)) (justify right))
    (property "Intersheetrefs" "${INTERSHEET_REFS}" (at 0.635 0.635 0)
      (effects (font (size 1.27 1.27)) hide)
    )
  )
  (global_label "I2C[8]_SCL" (shape input) (at 168.91 146.05 180) (fields_autoplaced)
    (effects (font (size 1.27 1.27)) (justify right))
    (property "Intersheetrefs" "${INTERSHEET_REFS}" (at 0.635 0.635 0)
      (effects (font (size 1.27 1.27)) hide)
    )
  )
  (global_label "I3C[3]_SDA_1V0" (shape input) (at 168.91 67.31 180) (fields_autoplaced)
    (effects (font (size 1.27 1.27)) (justify right))
    (property "Intersheetrefs" "${INTERSHEET_REFS}" (at 0.635 0.635 0)
      (effects (font (size 1.27 1.27)) hide)
    )
  )
  (global_label "QSPI1_D1" (shape input) (at 222.25 204.47 0) (fields_autoplaced)
    (effects (font (size 1.27 1.27)) (justify left))
    (property "Intersheetrefs" "${INTERSHEET_REFS}" (at -9.525 0.635 0)
      (effects (font (size 1.27 1.27)) hide)
    )
  )
  (global_label "SPARE1" (shape input) (at 168.91 219.71 180) (fields_autoplaced)
    (effects (font (size 1.27 1.27)) (justify right))
    (property "Intersheetrefs" "${INTERSHEET_REFS}" (at 0.635 0.635 0)
      (effects (font (size 1.27 1.27)) hide)
    )
  )
  (global_label "JTAG_TMS" (shape input) (at 168.91 171.45 180) (fields_autoplaced)
    (effects (font (size 1.27 1.27)) (justify right))
    (property "Intersheetrefs" "${INTERSHEET_REFS}" (at 0.635 0.635 0)
      (effects (font (size 1.27 1.27)) hide)
    )
  )
  (global_label "SGPIO0_CLK" (shape input) (at 326.39 81.28 0) (fields_autoplaced)
    (effects (font (size 1.27 1.27)) (justify left))
    (property "Intersheetrefs" "${INTERSHEET_REFS}" (at 48.26 -89.535 0)
      (effects (font (size 1.27 1.27)) hide)
    )
  )
  (global_label "SYS_PWROK" (shape input) (at 168.91 209.55 180) (fields_autoplaced)
    (effects (font (size 1.27 1.27)) (justify right))
    (property "Intersheetrefs" "${INTERSHEET_REFS}" (at 0.635 0.635 0)
      (effects (font (size 1.27 1.27)) hide)
    )
  )
  (global_label "I2C[4]_SCL" (shape input) (at 168.91 100.33 180) (fields_autoplaced)
    (effects (font (size 1.27 1.27)) (justify right))
    (property "Intersheetrefs" "${INTERSHEET_REFS}" (at 0.635 0.635 0)
      (effects (font (size 1.27 1.27)) hide)
    )
  )
  (global_label "SGPIO0_DO" (shape input) (at 222.25 156.21 0) (fields_autoplaced)
    (effects (font (size 1.27 1.27)) (justify left))
    (property "Intersheetrefs" "${INTERSHEET_REFS}" (at -9.525 0.635 0)
      (effects (font (size 1.27 1.27)) hide)
    )
  )
  (global_label "UART0_SCM_RX" (shape input) (at 222.25 59.69 0) (fields_autoplaced)
    (effects (font (size 1.27 1.27)) (justify left))
    (property "Intersheetrefs" "${INTERSHEET_REFS}" (at -9.525 0.635 0)
      (effects (font (size 1.27 1.27)) hide)
    )
  )
  (global_label "I3C[2]_SDA_1V0" (shape input) (at 168.91 62.23 180) (fields_autoplaced)
    (effects (font (size 1.27 1.27)) (justify right))
    (property "Intersheetrefs" "${INTERSHEET_REFS}" (at 0.635 0.635 0)
      (effects (font (size 1.27 1.27)) hide)
    )
  )
  (global_label "PCIE_HPM_TX1_P" (shape input) (at 222.25 245.11 0) (fields_autoplaced)
    (effects (font (size 1.27 1.27)) (justify left))
    (property "Intersheetrefs" "${INTERSHEET_REFS}" (at -9.525 0.635 0)
      (effects (font (size 1.27 1.27)) hide)
    )
  )
  (global_label "I2C[11]_SDA" (shape input) (at 168.91 181.61 180) (fields_autoplaced)
    (effects (font (size 1.27 1.27)) (justify right))
    (property "Intersheetrefs" "${INTERSHEET_REFS}" (at 0.635 0.635 0)
      (effects (font (size 1.27 1.27)) hide)
    )
  )
  (global_label "SGPIO1_DO" (shape input) (at 222.25 168.91 0) (fields_autoplaced)
    (effects (font (size 1.27 1.27)) (justify left))
    (property "Intersheetrefs" "${INTERSHEET_REFS}" (at -9.525 0.635 0)
      (effects (font (size 1.27 1.27)) hide)
    )
  )
  (global_label "JTAG_TCK" (shape input) (at 168.91 168.91 180) (fields_autoplaced)
    (effects (font (size 1.27 1.27)) (justify right))
    (property "Intersheetrefs" "${INTERSHEET_REFS}" (at 0.635 0.635 0)
      (effects (font (size 1.27 1.27)) hide)
    )
  )
  (global_label "I2C[0]_SDA" (shape input) (at 168.91 82.55 180) (fields_autoplaced)
    (effects (font (size 1.27 1.27)) (justify right))
    (property "Intersheetrefs" "${INTERSHEET_REFS}" (at 0.635 0.635 0)
      (effects (font (size 1.27 1.27)) hide)
    )
  )
  (global_label "PCIE_HPM_TX3_N" (shape input) (at 222.25 262.89 0) (fields_autoplaced)
    (effects (font (size 1.27 1.27)) (justify left))
    (property "Intersheetrefs" "${INTERSHEET_REFS}" (at -9.525 0.635 0)
      (effects (font (size 1.27 1.27)) hide)
    )
  )
  (global_label "HPM_FW_RECOVERY" (shape input) (at 168.91 196.85 180) (fields_autoplaced)
    (effects (font (size 1.27 1.27)) (justify right))
    (property "Intersheetrefs" "${INTERSHEET_REFS}" (at 0.635 0.635 0)
      (effects (font (size 1.27 1.27)) hide)
    )
  )
  (global_label "I2C[12]_SCL" (shape input) (at 168.91 184.15 180) (fields_autoplaced)
    (effects (font (size 1.27 1.27)) (justify right))
    (property "Intersheetrefs" "${INTERSHEET_REFS}" (at 0.635 0.635 0)
      (effects (font (size 1.27 1.27)) hide)
    )
  )
  (global_label "IRQ_N" (shape input) (at 168.91 229.87 180) (fields_autoplaced)
    (effects (font (size 1.27 1.27)) (justify right))
    (property "Intersheetrefs" "${INTERSHEET_REFS}" (at 0.635 0.635 0)
      (effects (font (size 1.27 1.27)) hide)
    )
  )
  (global_label "PCIE_HPM_TX1_N" (shape input) (at 222.25 247.65 0) (fields_autoplaced)
    (effects (font (size 1.27 1.27)) (justify left))
    (property "Intersheetrefs" "${INTERSHEET_REFS}" (at -9.525 0.635 0)
      (effects (font (size 1.27 1.27)) hide)
    )
  )
  (global_label "PCIE_HPM_RX1_P" (shape input) (at 168.91 245.11 180) (fields_autoplaced)
    (effects (font (size 1.27 1.27)) (justify right))
    (property "Intersheetrefs" "${INTERSHEET_REFS}" (at 0.635 0.635 0)
      (effects (font (size 1.27 1.27)) hide)
    )
  )
  (global_label "QSPI0_D3" (shape input) (at 222.25 118.11 0) (fields_autoplaced)
    (effects (font (size 1.27 1.27)) (justify left))
    (property "Intersheetrefs" "${INTERSHEET_REFS}" (at -9.525 0.635 0)
      (effects (font (size 1.27 1.27)) hide)
    )
  )
  (global_label "I2C[2]_SCL" (shape input) (at 168.91 90.17 180) (fields_autoplaced)
    (effects (font (size 1.27 1.27)) (justify right))
    (property "Intersheetrefs" "${INTERSHEET_REFS}" (at 0.635 0.635 0)
      (effects (font (size 1.27 1.27)) hide)
    )
  )
  (global_label "I2C[7]_SCL" (shape input) (at 168.91 140.97 180) (fields_autoplaced)
    (effects (font (size 1.27 1.27)) (justify right))
    (property "Intersheetrefs" "${INTERSHEET_REFS}" (at 0.635 0.635 0)
      (effects (font (size 1.27 1.27)) hide)
    )
  )
  (global_label "PCIE_BMC_TX_DP" (shape input) (at 168.91 120.65 180) (fields_autoplaced)
    (effects (font (size 1.27 1.27)) (justify right))
    (property "Intersheetrefs" "${INTERSHEET_REFS}" (at 0.635 0.635 0)
      (effects (font (size 1.27 1.27)) hide)
    )
  )
  (global_label "SPI0_CS_N" (shape input) (at 222.25 67.31 0) (fields_autoplaced)
    (effects (font (size 1.27 1.27)) (justify left))
    (property "Intersheetrefs" "${INTERSHEET_REFS}" (at -9.525 0.635 0)
      (effects (font (size 1.27 1.27)) hide)
    )
  )
  (global_label "QSPI1_D3" (shape input) (at 222.25 209.55 0) (fields_autoplaced)
    (effects (font (size 1.27 1.27)) (justify left))
    (property "Intersheetrefs" "${INTERSHEET_REFS}" (at -9.525 0.635 0)
      (effects (font (size 1.27 1.27)) hide)
    )
  )
  (global_label "QSPI1_D2" (shape input) (at 222.25 207.01 0) (fields_autoplaced)
    (effects (font (size 1.27 1.27)) (justify left))
    (property "Intersheetrefs" "${INTERSHEET_REFS}" (at -9.525 0.635 0)
      (effects (font (size 1.27 1.27)) hide)
    )
  )
  (global_label "SGPIO1_DI" (shape input) (at 222.25 173.99 0) (fields_autoplaced)
    (effects (font (size 1.27 1.27)) (justify left))
    (property "Intersheetrefs" "${INTERSHEET_REFS}" (at -9.525 0.635 0)
      (effects (font (size 1.27 1.27)) hide)
    )
  )
  (global_label "I2C[1]_SDA" (shape input) (at 168.91 87.63 180) (fields_autoplaced)
    (effects (font (size 1.27 1.27)) (justify right))
    (property "Intersheetrefs" "${INTERSHEET_REFS}" (at 0.635 0.635 0)
      (effects (font (size 1.27 1.27)) hide)
    )
  )
  (global_label "P12V_AUX" (shape input) (at 222.25 41.91 0) (fields_autoplaced)
    (effects (font (size 1.27 1.27)) (justify left))
    (property "Intersheetrefs" "${INTERSHEET_REFS}" (at -9.525 0.635 0)
      (effects (font (size 1.27 1.27)) hide)
    )
  )
  (global_label "I3C[0]_SCL_1V0" (shape input) (at 168.91 49.53 180) (fields_autoplaced)
    (effects (font (size 1.27 1.27)) (justify right))
    (property "Intersheetrefs" "${INTERSHEET_REFS}" (at 0.635 0.635 0)
      (effects (font (size 1.27 1.27)) hide)
    )
  )
  (global_label "NCSI_RXD0" (shape input) (at 222.25 138.43 0) (fields_autoplaced)
    (effects (font (size 1.27 1.27)) (justify left))
    (property "Intersheetrefs" "${INTERSHEET_REFS}" (at -9.525 0.635 0)
      (effects (font (size 1.27 1.27)) hide)
    )
  )
  (global_label "PCIE_BMC_RX_DP" (shape input) (at 168.91 128.27 180) (fields_autoplaced)
    (effects (font (size 1.27 1.27)) (justify right))
    (property "Intersheetrefs" "${INTERSHEET_REFS}" (at 0.635 0.635 0)
      (effects (font (size 1.27 1.27)) hide)
    )
  )

  (symbol (lib_id "antmicroPciConnectors:SFF-TA-1002-4C+") (at 182.88 39.37 0) (unit 1)
    (in_bom yes) (on_board yes) (dnp no) (fields_autoplaced)
    (property "Reference" "J5" (at 195.58 31.75 0)
      (effects (font (size 1.27 1.27)))
    )
    (property "Value" "SFF-TA-1002-4C+" (at 195.58 31.75 0)
      (effects (font (size 1.27 1.27)) hide)
    )
    (property "Footprint" "antmicro-footprints:SFF-TA-1002-4C+" (at 186.69 38.1 0)
      (effects (font (size 1.27 1.27)) hide)
    )
    (property "Datasheet" "https://cdn.amphenol-icc.com/media/wysiwyg/files/documentation/sme005.pdf?__cf_chl_jschl_tk__=4604d1306574a1ee474ea914090d3e0c57e266a6-1606907014-0-AbkYBTCTl__kMBcY3BDmgKpfUy32FqitwN2Lniuy8W-uyv2Ev04Q-Q5Mr7srIz_Wnur0_9chB4CRbxKSYcEh7IvAJYsUgJ0PWIS5YdRqqHg567uaZciEX2hQP4ss5l6M4XdNrxEjJppHvyRV3ku89t-VmUSzhgCb8oJlyHpTxST4dEmKZNXfM53TM0tmGirdVbCRt1Byrx5pkz_uMvNABIOj7B2-eDGK52J3DWRD76zEyjdxY7Iz11gPiOY5i_QGIR3uOwkR5LBPNXe8zGqAf8--AKa7RqDbIriQRt90_32C4zIuHqbGa05BXS135E65ov80PbVcb4eSiutCqcJUAacUwu3eVnXVeIumfihJxuP8Rv7_n6saeG_2IuQpEiskzovLGKZM3667Y-rm-AL1NRXTamtvBxqTk0vyMvZ60FgJ" (at 187.96 40.64 0)
      (effects (font (size 1.27 1.27)) hide)
    )
    (property "MPN" "SFF-TA-1002-4C+" (at 195.58 34.29 0)
      (effects (font (size 1.27 1.27) (thickness 0.15)))
    )
    (property "Manufacturer" "Amphenol" (at 229.87 52.07 0)
      (effects (font (size 1.27 1.27) (thickness 0.15)) (justify left bottom) hide)
    )
    (property "Author" "Antmicro" (at 229.87 54.61 0)
      (effects (font (size 1.27 1.27) (thickness 0.15)) (justify left bottom) hide)
    )
    (property "License" "Apache-2.0" (at 229.87 57.15 0)
      (effects (font (size 1.27 1.27) (thickness 0.15)) (justify left bottom) hide)
    )
    (property "DNP" "DNP" (at 182.88 39.37 0)
      (effects (font (size 1.27 1.27)) hide)
    )
    (pin "A1")
    (pin "A10")
    (pin "A11")
    (pin "A12")
    (pin "A13")
    (pin "A14")
    (pin "A15")
    (pin "A16")
    (pin "A17")
    (pin "A18")
    (pin "A19")
    (pin "A2")
    (pin "A20")
    (pin "A21")
    (pin "A22")
    (pin "A23")
    (pin "A24")
    (pin "A25")
    (pin "A26")
    (pin "A27")
    (pin "A28")
    (pin "A29")
    (pin "A3")
    (pin "A30")
    (pin "A31")
    (pin "A32")
    (pin "A33")
    (pin "A34")
    (pin "A35")
    (pin "A36")
    (pin "A37")
    (pin "A38")
    (pin "A39")
    (pin "A4")
    (pin "A40")
    (pin "A41")
    (pin "A42")
    (pin "A43")
    (pin "A44")
    (pin "A45")
    (pin "A46")
    (pin "A47")
    (pin "A48")
    (pin "A49")
    (pin "A5")
    (pin "A50")
    (pin "A51")
    (pin "A52")
    (pin "A53")
    (pin "A54")
    (pin "A55")
    (pin "A56")
    (pin "A57")
    (pin "A58")
    (pin "A59")
    (pin "A6")
    (pin "A60")
    (pin "A61")
    (pin "A62")
    (pin "A63")
    (pin "A64")
    (pin "A65")
    (pin "A66")
    (pin "A67")
    (pin "A68")
    (pin "A69")
    (pin "A7")
    (pin "A70")
    (pin "A8")
    (pin "A9")
    (pin "B1")
    (pin "B10")
    (pin "B11")
    (pin "B12")
    (pin "B13")
    (pin "B14")
    (pin "B15")
    (pin "B16")
    (pin "B17")
    (pin "B18")
    (pin "B19")
    (pin "B2")
    (pin "B20")
    (pin "B21")
    (pin "B22")
    (pin "B23")
    (pin "B24")
    (pin "B25")
    (pin "B26")
    (pin "B27")
    (pin "B28")
    (pin "B29")
    (pin "B3")
    (pin "B30")
    (pin "B31")
    (pin "B32")
    (pin "B33")
    (pin "B34")
    (pin "B35")
    (pin "B36")
    (pin "B37")
    (pin "B38")
    (pin "B39")
    (pin "B4")
    (pin "B40")
    (pin "B41")
    (pin "B42")
    (pin "B43")
    (pin "B44")
    (pin "B45")
    (pin "B46")
    (pin "B47")
    (pin "B48")
    (pin "B49")
    (pin "B5")
    (pin "B50")
    (pin "B51")
    (pin "B52")
    (pin "B53")
    (pin "B54")
    (pin "B55")
    (pin "B56")
    (pin "B57")
    (pin "B58")
    (pin "B59")
    (pin "B6")
    (pin "B60")
    (pin "B61")
    (pin "B62")
    (pin "B63")
    (pin "B64")
    (pin "B65")
    (pin "B66")
    (pin "B67")
    (pin "B68")
    (pin "B69")
    (pin "B7")
    (pin "B70")
    (pin "B8")
    (pin "B9")
    (pin "OA1")
    (pin "OA10")
    (pin "OA11")
    (pin "OA12")
    (pin "OA13")
    (pin "OA14")
    (pin "OA2")
    (pin "OA3")
    (pin "OA4")
    (pin "OA5")
    (pin "OA6")
    (pin "OA7")
    (pin "OA8")
    (pin "OA9")
    (pin "OB1")
    (pin "OB10")
    (pin "OB11")
    (pin "OB12")
    (pin "OB13")
    (pin "OB14")
    (pin "OB2")
    (pin "OB3")
    (pin "OB4")
    (pin "OB5")
    (pin "OB6")
    (pin "OB7")
    (pin "OB8")
    (pin "OB9")
    (instances
      (project "ecp5-dc-scm"
        (path ""
          (reference "J5") (unit 1)
        )
      )
    )
  )

  (symbol (lib_id "antmicroResistors0402:R_0R_0402") (at 317.5 81.28 0) (unit 1)
    (in_bom yes) (on_board yes) (dnp no) (fields_autoplaced)
    (property "Reference" "R47" (at 320.04 74.93 0)
      (effects (font (size 1.524 1.524)))
    )
    (property "Value" "R_0R_0402" (at 317.5 85.09 0)
      (effects (font (size 1.524 1.524)) hide)
    )
    (property "Footprint" "antmicro-footprints:R_0402_1005Metric" (at 322.58 76.2 0)
      (effects (font (size 1.524 1.524)) (justify left) hide)
    )
    (property "Datasheet" "https://industrial.panasonic.com/cdbs/www-data/pdf/RDA0000/AOA0000C301.pdf" (at 317.5 81.28 0)
      (effects (font (size 1.27 1.27)) hide)
    )
    (property "Manufacturer" "Panasonic" (at 322.58 71.12 0)
      (effects (font (size 1.524 1.524)) (justify left) hide)
    )
    (property "MPN" "ERJ2GE0R00X" (at 322.58 73.66 0)
      (effects (font (size 1.524 1.524)) (justify left) hide)
    )
    (property "Val" "0R" (at 320.04 77.47 0)
      (effects (font (size 1.27 1.27)))
    )
    (property "License" "Apache-2.0" (at 337.82 106.68 0)
      (effects (font (size 1.27 1.27) (thickness 0.15)) (justify left bottom) hide)
    )
    (property "Author" "Antmicro" (at 337.82 109.22 0)
      (effects (font (size 1.27 1.27) (thickness 0.15)) (justify left bottom) hide)
    )
    (property "Tolerance" "~" (at 337.82 91.44 0)
      (effects (font (size 1.27 1.27)) (justify left bottom) hide)
    )
    (property "Current" "1A" (at 337.82 111.76 0)
      (effects (font (size 1.27 1.27) (thickness 0.15)) (justify left bottom) hide)
    )
    (property "Public" "False" (at 337.82 111.76 0)
      (effects (font (size 1.27 1.27)) (justify left bottom) hide)
    )
    (pin "1")
    (pin "2")
    (instances
      (project "ecp5-dc-scm"
        (path ""
          (reference "R47") (unit 1)
        )
      )
    )
  )

  (symbol (lib_id "antmicropower:GND") (at 176.53 270.51 0) (unit 1)
    (in_bom yes) (on_board yes) (dnp no)
    (property "Reference" "#PWR027" (at 176.53 276.86 0)
      (effects (font (size 1.27 1.27)) hide)
    )
    (property "Value" "GND" (at 176.657 274.9042 0)
      (effects (font (size 1.27 1.27)))
    )
    (property "Footprint" "" (at 176.53 270.51 0)
      (effects (font (size 1.27 1.27)) hide)
    )
    (property "Datasheet" "" (at 176.53 270.51 0)
      (effects (font (size 1.27 1.27)) hide)
    )
    (property "Author" "Antmicro" (at 185.42 278.13 0)
      (effects (font (size 1.27 1.27) (thickness 0.15)) (justify left bottom) hide)
    )
    (property "License" "Apache-2.0" (at 185.42 280.67 0)
      (effects (font (size 1.27 1.27) (thickness 0.15)) (justify left bottom) hide)
    )
    (pin "1")
    (instances
      (project "ecp5-dc-scm"
        (path ""
          (reference "#PWR027") (unit 1)
        )
      )
    )
  )

  (symbol (lib_id "antmicropower:GND") (at 214.63 270.51 0) (unit 1)
    (in_bom yes) (on_board yes) (dnp no)
    (property "Reference" "#PWR028" (at 214.63 276.86 0)
      (effects (font (size 1.27 1.27)) hide)
    )
    (property "Value" "GND" (at 214.757 274.9042 0)
      (effects (font (size 1.27 1.27)))
    )
    (property "Footprint" "" (at 214.63 270.51 0)
      (effects (font (size 1.27 1.27)) hide)
    )
    (property "Datasheet" "" (at 214.63 270.51 0)
      (effects (font (size 1.27 1.27)) hide)
    )
    (property "Author" "Antmicro" (at 223.52 278.13 0)
      (effects (font (size 1.27 1.27) (thickness 0.15)) (justify left bottom) hide)
    )
    (property "License" "Apache-2.0" (at 223.52 280.67 0)
      (effects (font (size 1.27 1.27) (thickness 0.15)) (justify left bottom) hide)
    )
    (pin "1")
    (instances
      (project "ecp5-dc-scm"
        (path ""
          (reference "#PWR028") (unit 1)
        )
      )
    )
  )
)
